# T6G (Grand Teton) — schematic netlist excerpt (pin names and nets, part order shuffled) for the footprints in the layout excerpt that follows; sources: Cadence DE-HDL packaged netlist, KiCad conversion of 04192023_DAF0TMB3IC0_F0TG_MB_C_brd_V02_OCP.brd

C2051  Q_CAP  0.1UF 25V 10% X7R  pkg 0402  page 257 : A = P3V3_ADC128_VCC ; B = GND
R3488  Q_RES  1K 1% CHIP  pkg 0402LF  page 129 : A = P3V3_AUX ; B = GPU_FPGA_EROT_RST_N

(kicad_pcb
	(version 20260206)
	(generator "pcbnew")
	(generator_version "10.0")
	(general
		(thickness 1.6)
		(legacy_teardrops no)
	)
	(paper "A4")
	(title_block
		(title "04192023_DAF0TMB3IC0_F0TG_MB_C_brd_V02_OCP.brd")
		(comment 1 "Grand Teton / footprints 2315-2316 of 8354")
	)
	(layers
		(0 "F.Cu" signal "TOP")
		(4 "In1.Cu" signal "GND")
		(6 "In2.Cu" signal "IN1")
		(8 "In3.Cu" signal "GND1")
		(10 "In4.Cu" signal "IN2")
		(12 "In5.Cu" signal "GND2")
		(14 "In6.Cu" signal "IN3")
		(16 "In7.Cu" signal "GND3")
		(18 "In8.Cu" signal "VCC")
		(20 "In9.Cu" signal "VCC1")
		(22 "In10.Cu" signal "GND4")
		(24 "In11.Cu" signal "IN4")
		(26 "In12.Cu" signal "GND5")
		(28 "In13.Cu" signal "IN5")
		(30 "In14.Cu" signal "GND6")
		(32 "In15.Cu" signal "IN6")
		(34 "In16.Cu" signal "GND7")
		(2 "B.Cu" signal "BOTTOM")
		(9 "F.Adhes" user "F.Adhesive")
		(11 "B.Adhes" user "B.Adhesive")
		(13 "F.Paste" user "Package Geometry/Pastemask Top")
		(15 "B.Paste" user "Package Geometry/Pastemask Bottom")
		(5 "F.SilkS" user "Ref Des/Silkscreen Top")
		(7 "B.SilkS" user "Ref Des/Silkscreen Bottom")
		(1 "F.Mask" user "Board Geometry/Soldermask Top")
		(3 "B.Mask" user "Board Geometry/Soldermask Bottom")
		(17 "Dwgs.User" user "User.Drawings")
		(19 "Cmts.User" user "User.Comments")
		(21 "Eco1.User" user "User.Eco1")
		(23 "Eco2.User" user "User.Eco2")
		(25 "Edge.Cuts" user "Board Geometry/Outline")
		(27 "Margin" user)
		(31 "F.CrtYd" user "Package Geometry/Place Bound Top")
		(29 "B.CrtYd" user "Package Geometry/Place Bound Bottom")
		(35 "F.Fab" user "Ref Des/Assembly Top")
		(33 "B.Fab" user "Ref Des/Assembly Bottom")
	)
	(footprint ""
		(layer "F.Cu")
		(at 103.886 -426.466 -90)
		(property "Reference" "R3488"
			(at 0 0 270)
			(layer "F.SilkS")
			(hide yes)
			(effects
				(font
					(size 1.27 1.27)
				)
			)
		)
		(property "Value" ""
			(at 0 0 270)
			(layer "F.Fab")
			(effects
				(font
					(size 1.27 1.27)
				)
			)
		)
		(duplicate_pad_numbers_are_jumpers no)
		(fp_line
			(start -0.7874 0.4064)
			(end -0.7874 -0.4064)
			(stroke
				(width 0.1524)
				(type default)
			)
			(layer "F.SilkS")
		)
		(fp_line
			(start 0.7874 0.4064)
			(end -0.7874 0.4064)
			(stroke
				(width 0.1524)
				(type default)
			)
			(layer "F.SilkS")
		)
		(fp_line
			(start -0.7874 -0.4064)
			(end 0.7874 -0.4064)
			(stroke
				(width 0.1524)
				(type default)
			)
			(layer "F.SilkS")
		)
		(fp_line
			(start 0.7874 -0.4064)
			(end 0.7874 0.4064)
			(stroke
				(width 0.1524)
				(type default)
			)
			(layer "F.SilkS")
		)
		(fp_line
			(start -0.67945 0.3048)
			(end -0.67945 -0.305054)
			(stroke
				(width 0.1)
				(type default)
			)
			(layer "F.Fab")
		)
		(fp_line
			(start -0.12065 0.3048)
			(end -0.67945 0.3048)
			(stroke
				(width 0.1)
				(type default)
			)
			(layer "F.Fab")
		)
		(fp_line
			(start 0.120396 0.3048)
			(end 0.120396 0.2794)
			(stroke
				(width 0.1)
				(type default)
			)
			(layer "F.Fab")
		)
		(fp_line
			(start 0.67945 0.3048)
			(end 0.120396 0.3048)
			(stroke
				(width 0.1)
				(type default)
			)
			(layer "F.Fab")
		)
		(fp_line
			(start -0.12065 0.2794)
			(end -0.12065 0.3048)
			(stroke
				(width 0.1)
				(type default)
			)
			(layer "F.Fab")
		)
		(fp_line
			(start 0.120396 0.2794)
			(end -0.12065 0.2794)
			(stroke
				(width 0.1)
				(type default)
			)
			(layer "F.Fab")
		)
		(fp_line
			(start -0.12065 -0.2794)
			(end 0.12065 -0.2794)
			(stroke
				(width 0.1)
				(type default)
			)
			(layer "F.Fab")
		)
		(fp_line
			(start 0.12065 -0.2794)
			(end 0.12065 -0.3048)
			(stroke
				(width 0.1)
				(type default)
			)
			(layer "F.Fab")
		)
		(fp_line
			(start 0.12065 -0.3048)
			(end 0.67945 -0.3048)
			(stroke
				(width 0.1)
				(type default)
			)
			(layer "F.Fab")
		)
		(fp_line
			(start 0.67945 -0.3048)
			(end 0.67945 0.3048)
			(stroke
				(width 0.1)
				(type default)
			)
			(layer "F.Fab")
		)
		(fp_line
			(start -0.67945 -0.305054)
			(end -0.12065 -0.305054)
			(stroke
				(width 0.1)
				(type default)
			)
			(layer "F.Fab")
		)
		(fp_line
			(start -0.12065 -0.305054)
			(end -0.12065 -0.2794)
			(stroke
				(width 0.1)
				(type default)
			)
			(layer "F.Fab")
		)
		(pad "1" smd circle
			(at -0.40005 0 270)
			(size 0 0)
			(layers "F.Cu" "F.Mask" "F.Paste")
			(net "P3V3_AUX")
		)
		(pad "2" smd circle
			(at 0.40005 0 270)
			(size 0 0)
			(layers "F.Cu" "F.Mask" "F.Paste")
			(net "GPU_FPGA_EROT_RST_N")
		)
	)
	(footprint ""
		(layer "F.Cu")
		(at 303.200308 -45.005498 180)
		(property "Reference" "C2051"
			(at 0 0 180)
			(layer "F.SilkS")
			(hide yes)
			(effects
				(font
					(size 1.27 1.27)
				)
			)
		)
		(property "Value" ""
			(at 0 0 180)
			(layer "F.Fab")
			(effects
				(font
					(size 1.27 1.27)
				)
			)
		)
		(duplicate_pad_numbers_are_jumpers no)
		(fp_line
			(start 0.7874 0.4064)
			(end -0.7874 0.4064)
			(stroke
				(width 0.1524)
				(type default)
			)
			(layer "F.SilkS")
		)
		(fp_line
			(start 0.7874 -0.4064)
			(end 0.7874 0.4064)
			(stroke
				(width 0.1524)
				(type default)
			)
			(layer "F.SilkS")
		)
		(fp_line
			(start -0.7874 0.4064)
			(end -0.7874 -0.4064)
			(stroke
				(width 0.1524)
				(type default)
			)
			(layer "F.SilkS")
		)
		(fp_line
			(start -0.7874 -0.4064)
			(end 0.7874 -0.4064)
			(stroke
				(width 0.1524)
				(type default)
			)
			(layer "F.SilkS")
		)
		(fp_line
			(start 0.67945 0.3048)
			(end 0.120396 0.3048)
			(stroke
				(width 0.1)
				(type default)
			)
			(layer "F.Fab")
		)
		(fp_line
			(start 0.67945 -0.3048)
			(end 0.67945 0.3048)
			(stroke
				(width 0.1)
				(type default)
			)
			(layer "F.Fab")
		)
		(fp_line
			(start 0.12065 -0.2794)
			(end 0.12065 -0.3048)
			(stroke
				(width 0.1)
				(type default)
			)
			(layer "F.Fab")
		)
		(fp_line
			(start 0.12065 -0.3048)
			(end 0.67945 -0.3048)
			(stroke
				(width 0.1)
				(type default)
			)
			(layer "F.Fab")
		)
		(fp_line
			(start 0.120396 0.3048)
			(end 0.120396 0.2794)
			(stroke
				(width 0.1)
				(type default)
			)
			(layer "F.Fab")
		)
		(fp_line
			(start 0.120396 0.2794)
			(end -0.12065 0.2794)
			(stroke
				(width 0.1)
				(type default)
			)
			(layer "F.Fab")
		)
		(fp_line
			(start -0.12065 0.3048)
			(end -0.67945 0.3048)
			(stroke
				(width 0.1)
				(type default)
			)
			(layer "F.Fab")
		)
		(fp_line
			(start -0.12065 0.2794)
			(end -0.12065 0.3048)
			(stroke
				(width 0.1)
				(type default)
			)
			(layer "F.Fab")
		)
		(fp_line
			(start -0.12065 -0.2794)
			(end 0.12065 -0.2794)
			(stroke
				(width 0.1)
				(type default)
			)
			(layer "F.Fab")
		)
		(fp_line
			(start -0.12065 -0.305054)
			(end -0.12065 -0.2794)
			(stroke
				(width 0.1)
				(type default)
			)
			(layer "F.Fab")
		)
		(fp_line
			(start -0.67945 0.3048)
			(end -0.67945 -0.305054)
			(stroke
				(width 0.1)
				(type default)
			)
			(layer "F.Fab")
		)
		(fp_line
			(start -0.67945 -0.305054)
			(end -0.12065 -0.305054)
			(stroke
				(width 0.1)
				(type default)
			)
			(layer "F.Fab")
		)
		(pad "1" smd circle
			(at -0.40005 0 180)
			(size 0 0)
			(layers "F.Cu" "F.Mask" "F.Paste")
			(net "P3V3_ADC128_VCC")
		)
		(pad "2" smd circle
			(at 0.40005 0 180)
			(size 0 0)
			(layers "F.Cu" "F.Mask" "F.Paste")
			(net "GND")
		)
	)
)
